(kicad_pcb
	(version 20221018)
	(generator pcbnew)
	(general
    (thickness 1.7403)
  )
	(paper "A4")
	(title_block
    (title "Data Center RDIMM DDR4 Tester")
    (date "2024-09-30")
    (rev "1.2.4")
		(comment 9 "footprints 623-628 of 690")
	)
	(layers
    (0 "F.Cu" signal)
    (1 "In1.Cu" power)
    (2 "In2.Cu" signal)
    (3 "In3.Cu" power)
    (4 "In4.Cu" power)
    (5 "In5.Cu" signal)
    (6 "In6.Cu" power)
    (7 "In7.Cu" signal)
    (8 "In8.Cu" power)
    (9 "In9.Cu" signal)
    (10 "In10.Cu" power)
    (31 "B.Cu" signal)
    (32 "B.Adhes" user "B.Adhesive")
    (33 "F.Adhes" user "F.Adhesive")
    (34 "B.Paste" user)
    (35 "F.Paste" user)
    (36 "B.SilkS" user "B.Silkscreen")
    (37 "F.SilkS" user "F.Silkscreen")
    (38 "B.Mask" user)
    (39 "F.Mask" user)
    (40 "Dwgs.User" user "User.Drawings")
    (41 "Cmts.User" user "User.Comments")
    (42 "Eco1.User" user "User.Eco1")
    (43 "Eco2.User" user "User.Eco2")
    (44 "Edge.Cuts" user)
    (45 "Margin" user)
    (46 "B.CrtYd" user "B.Courtyard")
    (47 "F.CrtYd" user "F.Courtyard")
    (48 "B.Fab" user)
    (49 "F.Fab" user)
  )
	(footprint "data-center-rdimm-ddr4-tester-footprints:VQFN-16-1EP_3x3mm_P0.5mm_EP1.1x1.1mm" (layer "B.Cu")
    (at 126.8 90.8 -90)
    (descr "VQFN, 16 Pin (https://ww1.microchip.com/downloads/en/DeviceDoc/16L_VQFN-WFS_3x3mm_4MX_C04-00508a.pdf), generated with kicad-footprint-generator ipc_noLead_generator.py")
    (tags "VQFN NoLead")
    (property "Author" "Antmicro")
    (property "License" "Apache-2.0")
    (property "MPN" "PAC1954T-E/4MX")
    (property "Manufacturer" "Microchip Technology")
    (property "Sheetfile" "supply.kicad_sch")
    (property "Sheetname" "Supply")
    (property "ki_description" "Current/Voltage Monitor Regulator High-Side 16-VQFN (3x3)")
    (property "ki_keywords" "MONITOR, VOLTAGE")
    (attr smd)
    (fp_text reference "U20" (at 3.18 1.07 -180) (layer "B.SilkS")
        (effects (font (size 0.7 0.7) (thickness 0.15)) (justify left bottom mirror))
    )
    (fp_text value "PAC1954T-E_VQFN" (at 0 -2.797 90) (layer "B.Fab")
        (effects (font (size 0.7 0.7) (thickness 0.15)) (justify left bottom mirror))
    )
    (fp_text user "Author: Antmicro" (at -2.35 -5.997 90) (layer "B.Fab") hide
        (effects (font (size 0.7 0.7) (thickness 0.15)) (justify left bottom mirror))
    )
    (fp_text user "License: Apache-2.0" (at -2.35 -7.197 90) (layer "B.Fab") hide
        (effects (font (size 0.7 0.7) (thickness 0.15)) (justify left bottom mirror))
    )
    (fp_text user "${REFERENCE}" (at -2.35 -4.797 90) (layer "B.Fab") hide
        (effects (font (size 0.7 0.7) (thickness 0.15)) (justify left bottom mirror))
    )
    (fp_line (start -1.611 -1.61) (end -1.611 -1.134)
      (stroke (width 0.15) (type solid)) (layer "B.SilkS"))
    (fp_line (start -1.135 -1.61) (end -1.611 -1.61)
      (stroke (width 0.15) (type solid)) (layer "B.SilkS"))
    (fp_line (start -1.135 1.611) (end -1.611 1.611)
      (stroke (width 0.15) (type solid)) (layer "B.SilkS"))
    (fp_line (start 1.134 -1.61) (end 1.61 -1.61)
      (stroke (width 0.15) (type solid)) (layer "B.SilkS"))
    (fp_line (start 1.134 1.611) (end 1.61 1.611)
      (stroke (width 0.15) (type solid)) (layer "B.SilkS"))
    (fp_line (start 1.61 -1.61) (end 1.61 -1.134)
      (stroke (width 0.15) (type solid)) (layer "B.SilkS"))
    (fp_line (start 1.61 1.611) (end 1.61 1.135)
      (stroke (width 0.15) (type solid)) (layer "B.SilkS"))
    (fp_circle (center -2.3 0.75) (end -2.25 0.75)
      (stroke (width 0.15) (type solid)) (fill solid) (layer "B.SilkS"))
    (fp_rect (start -2 2) (end 1.999 -1.999)
      (stroke (width 0.05) (type solid)) (fill none) (layer "B.CrtYd"))
    (fp_line (start -1.5 -1.499) (end -1.5 0.75)
      (stroke (width 0.15) (type solid)) (layer "B.Fab"))
    (fp_line (start -1.5 0.75) (end -0.75 1.5)
      (stroke (width 0.15) (type solid)) (layer "B.Fab"))
    (fp_line (start -0.75 1.5) (end 1.499 1.5)
      (stroke (width 0.15) (type solid)) (layer "B.Fab"))
    (fp_line (start 1.499 -1.499) (end -1.5 -1.499)
      (stroke (width 0.15) (type solid)) (layer "B.Fab"))
    (fp_line (start 1.499 1.5) (end 1.499 -1.499)
      (stroke (width 0.15) (type solid)) (layer "B.Fab"))
    (fp_circle (center -2.3 0.75) (end -2.25 0.75)
      (stroke (width 0.15) (type solid)) (fill solid) (layer "B.Fab"))
    (pad "" smd roundrect (at 0 0 270) (size 0.89 0.89) (layers "B.Paste") (roundrect_rratio 0.25))
    (pad "1" smd roundrect (at -1.464 0.75 270) (size 0.775 0.25) (layers "B.Cu" "B.Paste" "B.Mask") (roundrect_rratio 0.25)
      (net 9 "GND") (pinfunction "SLOW/~{ALERT1}") (pintype "bidirectional"))
    (pad "2" smd roundrect (at -1.464 0.25 270) (size 0.775 0.25) (layers "B.Cu" "B.Paste" "B.Mask") (roundrect_rratio 0.25)
      (net 143 "3V3_SYS") (pinfunction "VDD") (pintype "power_in"))
    (pad "3" smd roundrect (at -1.464 -0.247 270) (size 0.775 0.25) (layers "B.Cu" "B.Paste" "B.Mask") (roundrect_rratio 0.25)
      (net 9 "GND") (pinfunction "GND") (pintype "power_in"))
    (pad "4" smd roundrect (at -1.464 -0.747 270) (size 0.775 0.25) (layers "B.Cu" "B.Paste" "B.Mask") (roundrect_rratio 0.25)
      (net 358 "SCL_3V3") (pinfunction "SCL") (pintype "input"))
    (pad "5" smd roundrect (at -0.75 -1.461 270) (size 0.25 0.775) (layers "B.Cu" "B.Paste" "B.Mask") (roundrect_rratio 0.25)
      (net 357 "SDA_3V3") (pinfunction "SDA") (pintype "bidirectional"))
    (pad "6" smd roundrect (at -0.25 -1.461 270) (size 0.25 0.775) (layers "B.Cu" "B.Paste" "B.Mask") (roundrect_rratio 0.25)
      (net 143 "3V3_SYS") (pinfunction "ADDRSEL") (pintype "bidirectional"))
    (pad "7" smd roundrect (at 0.247 -1.461 270) (size 0.25 0.775) (layers "B.Cu" "B.Paste" "B.Mask") (roundrect_rratio 0.25)
      (net 844 "/Supply/1V8_SEN_-") (pinfunction "IN3-") (pintype "input"))
    (pad "8" smd roundrect (at 0.747 -1.461 270) (size 0.25 0.775) (layers "B.Cu" "B.Paste" "B.Mask") (roundrect_rratio 0.25)
      (net 840 "/Supply/1V8_SEN_+") (pinfunction "IN3+") (pintype "input"))
    (pad "9" smd roundrect (at 1.461 -0.747 270) (size 0.775 0.25) (layers "B.Cu" "B.Paste" "B.Mask") (roundrect_rratio 0.25)
      (net 845 "/Supply/1V0_SEN_-") (pinfunction "IN4-") (pintype "input"))
    (pad "10" smd roundrect (at 1.461 -0.247 270) (size 0.775 0.25) (layers "B.Cu" "B.Paste" "B.Mask") (roundrect_rratio 0.25)
      (net 841 "/Supply/1V0_SEN_+") (pinfunction "IN4+") (pintype "input"))
    (pad "11" smd roundrect (at 1.461 0.25 270) (size 0.775 0.25) (layers "B.Cu" "B.Paste" "B.Mask") (roundrect_rratio 0.25)
      (net 838 "/Supply/5V0_SEN_+") (pinfunction "IN1+") (pintype "input"))
    (pad "12" smd roundrect (at 1.461 0.75 270) (size 0.775 0.25) (layers "B.Cu" "B.Paste" "B.Mask") (roundrect_rratio 0.25)
      (net 842 "/Supply/5V0_SEN_-") (pinfunction "IN1-") (pintype "input"))
    (pad "13" smd roundrect (at 0.747 1.464 270) (size 0.25 0.775) (layers "B.Cu" "B.Paste" "B.Mask") (roundrect_rratio 0.25)
      (net 839 "/Supply/3V3_SEN_+") (pinfunction "IN2+") (pintype "input"))
    (pad "14" smd roundrect (at 0.247 1.464 270) (size 0.25 0.775) (layers "B.Cu" "B.Paste" "B.Mask") (roundrect_rratio 0.25)
      (net 843 "/Supply/3V3_SEN_-") (pinfunction "IN2-") (pintype "input"))
    (pad "15" smd roundrect (at -0.25 1.464 270) (size 0.25 0.775) (layers "B.Cu" "B.Paste" "B.Mask") (roundrect_rratio 0.25)
      (net 9 "GND") (pinfunction "GPIO/~{ALERT2}") (pintype "bidirectional"))
    (pad "16" smd roundrect (at -0.75 1.464 270) (size 0.25 0.775) (layers "B.Cu" "B.Paste" "B.Mask") (roundrect_rratio 0.25)
      (net 661 "Net-(U20-~{PWRDN})") (pinfunction "~{PWRDN}") (pintype "input"))
    (pad "17" smd rect (at 0 0 270) (size 1.1 1.1) (layers "B.Cu" "B.Mask")
      (net 918 "unconnected-(U20-EP-Pad17)") (pinfunction "EP") (pintype "no_connect"))
  )
	(footprint "data-center-rdimm-ddr4-tester-footprints:SC-74-6_1.5x2.9mm_P0.95mm" (layer "B.Cu")
    (at 140 79.7 -90)
    (descr "https://assets.nexperia.com/documents/data-sheet/IP4220CZ6.pdf")
    (tags "sc74 sc-74 sot23-6 sot457 tsop6 tsop-6")
    (property "Author" "Antmicro")
    (property "License" "Apache-2.0")
    (property "MPN" "74LVC2G07GV,125")
    (property "Manufacturer" "Nexperia")
    (property "Sheetfile" "supply.kicad_sch")
    (property "Sheetname" "Supply")
    (property "ki_description" "Dual Buffer w/ Open Drain, Low-Voltage CMOS, TSOP6 (SOT457/SC-74/SOT23-6) package 1.1mm height, Texas Instruments Equivalent: SN74LVC2G07DBVR")
    (property "ki_keywords" "Dual Gate Buffer Open Drain LVC CMOS")
    (attr smd)
    (fp_text reference "U17" (at -1.63 -3.36 180) (layer "B.SilkS")
        (effects (font (size 0.7 0.7) (thickness 0.15)) (justify left bottom mirror))
    )
    (fp_text value "74LVC2G07_SOT457" (at -2 -2.999 90) (layer "B.Fab") hide
        (effects (font (size 0.7 0.7) (thickness 0.15)) (justify left bottom mirror))
    )
    (fp_text user "Author: Antmicro" (at -2.12 -4.999 90) (layer "B.Fab") hide
        (effects (font (size 0.7 0.7) (thickness 0.15)) (justify left bottom mirror))
    )
    (fp_text user "${REFERENCE}" (at -2.12 -7.399 90) (layer "B.Fab") hide
        (effects (font (size 0.7 0.7) (thickness 0.15)) (justify left bottom mirror))
    )
    (fp_text user "License: Apache-2.0" (at -2.12 -6.199 90) (layer "B.Fab") hide
        (effects (font (size 0.7 0.7) (thickness 0.15)) (justify left bottom mirror))
    )
    (fp_circle (center -2.07 0.956) (end -2.02 0.956)
      (stroke (width 0.15) (type solid)) (fill solid) (layer "B.SilkS"))
    (fp_circle (center -2.069 0.956) (end -2.02 0.956)
      (stroke (width 0.15) (type solid)) (fill solid) (layer "B.SilkS"))
    (fp_rect (start -1.714 1.897) (end 1.711 -1.896)
      (stroke (width 0.05) (type solid)) (fill none) (layer "B.CrtYd"))
    (fp_line (start -1.27 -1.372) (end -1.168 -1.372)
      (stroke (width 0.15) (type solid)) (layer "B.Fab"))
    (fp_line (start -1.27 0.915) (end -1.27 -1.372)
      (stroke (width 0.15) (type solid)) (layer "B.Fab"))
    (fp_line (start -1.168 -1.372) (end 1.219 -1.372)
      (stroke (width 0.15) (type solid)) (layer "B.Fab"))
    (fp_line (start -0.761 1.422) (end -1.27 0.915)
      (stroke (width 0.15) (type solid)) (layer "B.Fab"))
    (fp_line (start 1.219 -1.372) (end 1.219 1.422)
      (stroke (width 0.15) (type solid)) (layer "B.Fab"))
    (fp_line (start 1.219 1.422) (end -0.761 1.422)
      (stroke (width 0.15) (type solid)) (layer "B.Fab"))
    (fp_circle (center -2.069 0.956) (end -2.02 0.956)
      (stroke (width 0.15) (type solid)) (fill solid) (layer "B.Fab"))
    (pad "1" smd roundrect (at -1.214 0.955 270) (size 0.8 0.55) (layers "B.Cu" "B.Paste" "B.Mask") (roundrect_rratio 0.15)
      (net 152 "/Supply/VCC_AUX_EN") (pintype "input"))
    (pad "2" smd roundrect (at -1.214 0.003 270) (size 0.8 0.55) (layers "B.Cu" "B.Paste" "B.Mask") (roundrect_rratio 0.15)
      (net 9 "GND") (pinfunction "GND") (pintype "power_in"))
    (pad "3" smd roundrect (at -1.214 -0.947 270) (size 0.8 0.55) (layers "B.Cu" "B.Paste" "B.Mask") (roundrect_rratio 0.15)
      (net 151 "/Supply/VCC_INT_EN") (pintype "input"))
    (pad "4" smd roundrect (at 1.187 -0.947 270) (size 0.8 0.55) (layers "B.Cu" "B.Paste" "B.Mask") (roundrect_rratio 0.15)
      (net 855 "Net-(R29-Pad1)") (pintype "output"))
    (pad "5" smd roundrect (at 1.187 0.003 270) (size 0.8 0.55) (layers "B.Cu" "B.Paste" "B.Mask") (roundrect_rratio 0.15)
      (net 307 "5V0_SYS") (pinfunction "V_{CC}") (pintype "power_in"))
    (pad "6" smd roundrect (at 1.187 0.955 270) (size 0.8 0.55) (layers "B.Cu" "B.Paste" "B.Mask") (roundrect_rratio 0.15)
      (net 854 "Net-(R17-Pad1)") (pintype "output"))
  )
	(footprint "data-center-rdimm-ddr4-tester-footprints:FB_0805_2012Metric" (layer "B.Cu")
    (at 184.1 123.6 -90)
    (property "Author" "Antmicro")
    (property "License" "Apache-2.0")
    (property "MPN" "BLM21PG221SN1D")
    (property "Manufacturer" "Murata")
    (property "Sheetfile" "ethernet.kicad_sch")
    (property "Sheetname" "Ethernet")
    (attr smd)
    (fp_text reference "FB10" (at -1.19 -1.78 90) (layer "B.SilkS")
        (effects (font (size 0.7 0.7) (thickness 0.15)) (justify left bottom mirror))
    )
    (fp_text value "FB_220Z_2A_0603" (at 0 -1.8 90) (layer "B.Fab") hide
        (effects (font (size 0.7 0.7) (thickness 0.15)) (justify left bottom mirror))
    )
    (fp_text user "Author: Antmicro" (at -1.9 -4.4 90) (layer "B.Fab") hide
        (effects (font (size 0.7 0.7) (thickness 0.15)) (justify left bottom mirror))
    )
    (fp_text user "${REFERENCE}" (at -1.9 -3.1 90) (layer "B.Fab") hide
        (effects (font (size 0.7 0.7) (thickness 0.15)) (justify left bottom mirror))
    )
    (fp_text user "License: Apache-2.0" (at -1.9 -5.75 90) (layer "B.Fab") hide
        (effects (font (size 0.7 0.7) (thickness 0.15)) (justify left bottom mirror))
    )
    (fp_line (start -0.32 -0.699) (end 0.28 -0.699)
      (stroke (width 0.15) (type solid)) (layer "B.SilkS"))
    (fp_line (start -0.3 0.701) (end 0.298 0.701)
      (stroke (width 0.15) (type solid)) (layer "B.SilkS"))
    (fp_rect (start -1.75 0.85) (end 1.75 -0.85)
      (stroke (width 0.05) (type solid)) (fill none) (layer "B.CrtYd"))
    (fp_line (start -0.951 -0.68) (end 0.949 -0.68)
      (stroke (width 0.15) (type solid)) (layer "B.Fab"))
    (fp_line (start -0.951 0.677) (end -0.951 -0.675)
      (stroke (width 0.15) (type solid)) (layer "B.Fab"))
    (fp_line (start -0.951 0.682) (end 0.949 0.682)
      (stroke (width 0.15) (type solid)) (layer "B.Fab"))
    (fp_line (start 0.949 0.677) (end 0.949 -0.675)
      (stroke (width 0.15) (type solid)) (layer "B.Fab"))
    (pad "1" smd roundrect (at -1.1 0.001 270) (size 1 1.4) (layers "B.Cu" "B.Paste" "B.Mask") (roundrect_rratio 0.15)
      (net 807 "/Ethernet/VSS_RAW") (pintype "passive"))
    (pad "2" smd roundrect (at 1.1 0.001 270) (size 1 1.4) (layers "B.Cu" "B.Paste" "B.Mask") (roundrect_rratio 0.15)
      (net 381 "/Ethernet/VSS") (pintype "passive"))
  )
	(footprint "data-center-rdimm-ddr4-tester-footprints:R_0603_1608Metric" (layer "B.Cu")
    (at 181.91 124.8 180)
    (descr "Resistor SMD 0603")
    (tags "resistor SMD 0603")
    (property "Author" "Antmicro")
    (property "License" "Apache-2.0")
    (property "MPN" "CR0603-FX-63R4ELF")
    (property "Manufacturer" "Bourns")
    (property "Sheetfile" "ethernet.kicad_sch")
    (property "Sheetname" "Ethernet")
    (property "Tolerance" "1%")
    (property "Val" "63R4")
    (property "ki_description" "63R4 resistor in 0603 package with 1% tolerance")
    (attr smd)
    (fp_text reference "R85" (at -8.53 3.9) (layer "B.SilkS")
        (effects (font (size 0.7 0.7) (thickness 0.15)) (justify left bottom mirror))
    )
    (fp_text value "R_63R4_0603" (at 0 -1.6) (layer "B.Fab") hide
        (effects (font (size 0.7 0.7) (thickness 0.15)) (justify left bottom mirror))
    )
    (fp_text user "Author: Antmicro" (at -1.25 -4.9) (layer "B.Fab") hide
        (effects (font (size 0.7 0.7) (thickness 0.15)) (justify left bottom mirror))
    )
    (fp_text user "License: Apache-2.0" (at -1.25 -5.9) (layer "B.Fab") hide
        (effects (font (size 0.7 0.7) (thickness 0.15)) (justify left bottom mirror))
    )
    (fp_text user "${REFERENCE}" (at -1.25 -3.898) (layer "B.Fab") hide
        (effects (font (size 0.7 0.7) (thickness 0.15)) (justify left bottom mirror))
    )
    (fp_line (start -0.3 -0.3) (end 0.3 -0.3)
      (stroke (width 0.15) (type solid)) (layer "B.SilkS"))
    (fp_line (start -0.3 0.3) (end 0.3 0.3)
      (stroke (width 0.15) (type solid)) (layer "B.SilkS"))
    (fp_rect (start -1.25 0.7) (end 1.25 -0.7)
      (stroke (width 0.05) (type solid)) (fill none) (layer "B.CrtYd"))
    (fp_rect (start -0.8 0.4) (end 0.8 -0.4)
      (stroke (width 0.15) (type solid)) (fill none) (layer "B.Fab"))
    (pad "1" smd roundrect (at -0.7 0 180) (size 0.6 0.8) (layers "B.Cu" "B.Paste" "B.Mask") (roundrect_rratio 0.2)
      (net 381 "/Ethernet/VSS") (pintype "passive"))
    (pad "2" smd roundrect (at 0.7 0 180) (size 0.6 0.8) (layers "B.Cu" "B.Paste" "B.Mask") (roundrect_rratio 0.2)
      (net 611 "/Ethernet/CLSA") (pintype "passive"))
  )
	(footprint "data-center-rdimm-ddr4-tester-footprints:R_0603_1608Metric" (layer "B.Cu")
    (at 185.5 126.2 180)
    (descr "Resistor SMD 0603")
    (tags "resistor SMD 0603")
    (property "Author" "Antmicro")
    (property "License" "Apache-2.0")
    (property "MPN" "CR0603-FX-63R4ELF")
    (property "Manufacturer" "Bourns")
    (property "Sheetfile" "ethernet.kicad_sch")
    (property "Sheetname" "Ethernet")
    (property "Tolerance" "1%")
    (property "Val" "63R4")
    (property "ki_description" "63R4 resistor in 0603 package with 1% tolerance")
    (attr smd)
    (fp_text reference "R176" (at -3.92 -0.4) (layer "B.SilkS")
        (effects (font (size 0.7 0.7) (thickness 0.15)) (justify left bottom mirror))
    )
    (fp_text value "R_63R4_0603" (at 0 -1.6) (layer "B.Fab") hide
        (effects (font (size 0.7 0.7) (thickness 0.15)) (justify left bottom mirror))
    )
    (fp_text user "Author: Antmicro" (at -1.25 -4.9) (layer "B.Fab") hide
        (effects (font (size 0.7 0.7) (thickness 0.15)) (justify left bottom mirror))
    )
    (fp_text user "License: Apache-2.0" (at -1.25 -5.9) (layer "B.Fab") hide
        (effects (font (size 0.7 0.7) (thickness 0.15)) (justify left bottom mirror))
    )
    (fp_text user "${REFERENCE}" (at -1.25 -3.898) (layer "B.Fab") hide
        (effects (font (size 0.7 0.7) (thickness 0.15)) (justify left bottom mirror))
    )
    (fp_line (start -0.3 -0.3) (end 0.3 -0.3)
      (stroke (width 0.15) (type solid)) (layer "B.SilkS"))
    (fp_line (start -0.3 0.3) (end 0.3 0.3)
      (stroke (width 0.15) (type solid)) (layer "B.SilkS"))
    (fp_rect (start -1.25 0.7) (end 1.25 -0.7)
      (stroke (width 0.05) (type solid)) (fill none) (layer "B.CrtYd"))
    (fp_rect (start -0.8 0.4) (end 0.8 -0.4)
      (stroke (width 0.15) (type solid)) (fill none) (layer "B.Fab"))
    (pad "1" smd roundrect (at -0.7 0 180) (size 0.6 0.8) (layers "B.Cu" "B.Paste" "B.Mask") (roundrect_rratio 0.2)
      (net 381 "/Ethernet/VSS") (pintype "passive"))
    (pad "2" smd roundrect (at 0.7 0 180) (size 0.6 0.8) (layers "B.Cu" "B.Paste" "B.Mask") (roundrect_rratio 0.2)
      (net 618 "/Ethernet/CLSB") (pintype "passive"))
  )
	(footprint "data-center-rdimm-ddr4-tester-footprints:R_0402_1005Metric" (layer "B.Cu")
    (at 127.525 108.425 90)
    (descr "Resistor SMD 0402")
    (tags "resistor SMD 0402")
    (property "Author" "Antmicro")
    (property "License" "Apache-2.0")
    (property "MPN" "CR0402-FX-1003GLF")
    (property "Manufacturer" "Bourns")
    (property "Sheetfile" "supply.kicad_sch")
    (property "Sheetname" "Supply")
    (property "Tolerance" "1%")
    (property "Val" "100k")
    (property "ki_description" "100k resistor in 0402 package with 1% tolerance")
    (attr smd)
    (fp_text reference "R212" (at 1.265 -0.575 270) (layer "B.SilkS")
        (effects (font (size 0.7 0.7) (thickness 0.15)) (justify left bottom mirror))
    )
    (fp_text value "R_100k_0402" (at 0 -1.4 270) (layer "B.Fab") hide
        (effects (font (size 0.7 0.7) (thickness 0.15)) (justify left bottom mirror))
    )
    (fp_text user "${REFERENCE}" (at -0.95 -3.168 270) (layer "B.Fab") hide
        (effects (font (size 0.7 0.7) (thickness 0.15)) (justify left bottom mirror))
    )
    (fp_text user "Author: Antmicro" (at -0.95 -4.169 270) (layer "B.Fab") hide
        (effects (font (size 0.7 0.7) (thickness 0.15)) (justify left bottom mirror))
    )
    (fp_text user "License: Apache-2.0" (at -0.95 -5.169 270) (layer "B.Fab") hide
        (effects (font (size 0.7 0.7) (thickness 0.15)) (justify left bottom mirror))
    )
    (fp_rect (start -0.93 0.47) (end 0.93 -0.47)
      (stroke (width 0.05) (type solid)) (fill none) (layer "B.CrtYd"))
    (fp_rect (start -0.5 0.25) (end 0.5 -0.25)
      (stroke (width 0.15) (type solid)) (fill none) (layer "B.Fab"))
    (pad "1" smd roundrect (at -0.485 0 90) (size 0.59 0.64) (layers "B.Cu" "B.Paste" "B.Mask") (roundrect_rratio 0.25)
      (net 9 "GND") (pintype "passive"))
    (pad "2" smd roundrect (at 0.485 0 90) (size 0.59 0.64) (layers "B.Cu" "B.Paste" "B.Mask") (roundrect_rratio 0.25)
      (net 798 "/Supply/FPGA_PWR_DIS") (pintype "passive"))
  )
)
